(kicad_pcb
	(version 20260206)
	(generator "pcbnew")
	(generator_version "10.0")
	(general
		(thickness 1.6)
		(legacy_teardrops no)
	)
	(paper "A4")
	(title_block
		(title "panther-plus-userver — 13130-1b_20150205.brd")
		(comment 1 "Honey Badger (Wiwynn) / footprint 894 of 1509 (DIMM1), pads 9-15 of 210")
	)
	(layers
		(0 "F.Cu" signal "TOP")
		(4 "In1.Cu" signal "L2")
		(6 "In2.Cu" signal "L3")
		(8 "In3.Cu" signal "L4")
		(10 "In4.Cu" signal "L5")
		(12 "In5.Cu" signal "L6")
		(14 "In6.Cu" signal "L7")
		(16 "In7.Cu" signal "L8")
		(18 "In8.Cu" signal "L9")
		(20 "In9.Cu" signal "L10")
		(22 "In10.Cu" signal "L11")
		(2 "B.Cu" signal "BOTTOM")
		(9 "F.Adhes" user "F.Adhesive")
		(11 "B.Adhes" user "B.Adhesive")
		(13 "F.Paste" user "Package Geometry/Pastemask Top")
		(15 "B.Paste" user "Package Geometry/Pastemask Bottom")
		(5 "F.SilkS" user "Ref Des/Silkscreen Top")
		(7 "B.SilkS" user "Ref Des/Silkscreen Bottom")
		(1 "F.Mask" user "Board Geometry/Soldermask Top")
		(3 "B.Mask" user "Board Geometry/Soldermask Bottom")
		(17 "Dwgs.User" user "User.Drawings")
		(19 "Cmts.User" user "User.Comments")
		(21 "Eco1.User" user "User.Eco1")
		(23 "Eco2.User" user "User.Eco2")
		(25 "Edge.Cuts" user "Board Geometry/Outline")
		(27 "Margin" user)
		(31 "F.CrtYd" user "Package Geometry/Place Bound Top")
		(29 "B.CrtYd" user "Package Geometry/Place Bound Bottom")
		(35 "F.Fab" user "Ref Des/Assembly Top")
		(33 "B.Fab" user "Ref Des/Assembly Bottom")
	)
	(footprint ""
		(layer "B.Cu")
		(at 158.500064 -66.699892 180)
		(property "Reference" "DIMM1"
			(at 0 0 0)
			(layer "B.SilkS")
			(hide yes)
			(effects
				(font
					(size 1.27 1.27)
				)
				(justify mirror)
			)
		)
		(property "Value" "DDR3-204P-142-COLAY-1-GP-U"
			(at 41.312338 -16.676878 180)
			(unlocked yes)
			(layer "B.Fab")
			(hide yes)
			(effects
				(font
					(size 1.016 1.016)
					(thickness 0.1524)
				)
				(justify mirror)
			)
		)
		(property "Device Type" "AS0A626-J8R6-7H-COLAY-1"
			(at 41.312338 -18.200878 180)
			(unlocked yes)
			(layer "B.Fab")
			(hide yes)
			(effects
				(font
					(size 1.016 1.016)
					(thickness 0.1524)
				)
				(justify mirror)
			)
		)
		(duplicate_pad_numbers_are_jumpers no)
		(pad "7" smd custom
			(at -29.85008 -4.100068)
			(size 0.1143 0.1143)
			(layers "B.Cu" "B.Mask" "B.Paste")
			(net "M_A_DQ1")
			(options
				(clearance outline)
				(anchor circle)
			)
			(primitives
				(gr_poly
					(pts
						(xy 0 -0.9017) (xy -0.03175 -0.89916) (xy -0.0635 -0.889) (xy -0.09144 -0.87376) (xy -0.11684 -0.85344)
						(xy -0.13716 -0.82804) (xy -0.1524 -0.8001) (xy -0.16256 -0.76835) (xy -0.1651 -0.7366) (xy -0.1651 -0.19685)
						(xy -0.17272 -0.18923) (xy -0.17907 -0.18034) (xy -0.18669 -0.17145) (xy -0.19177 -0.16256) (xy -0.19812 -0.15367)
						(xy -0.20828 -0.13335) (xy -0.21971 -0.10287) (xy -0.22225 -0.09271) (xy -0.22479 -0.08128) (xy -0.22606 -0.07112)
						(xy -0.2286 -0.05969) (xy -0.2286 -0.01651) (xy -0.22606 -0.00508) (xy -0.22479 0.00508) (xy -0.22225 0.01651)
						(xy -0.21971 0.02667) (xy -0.20828 0.05715) (xy -0.19812 0.07747) (xy -0.19177 0.08636) (xy -0.18669 0.09525)
						(xy -0.17907 0.10414) (xy -0.17272 0.11303) (xy -0.1651 0.12065) (xy -0.1651 0.7366) (xy -0.16256 0.76835)
						(xy -0.1524 0.8001) (xy -0.13716 0.82804) (xy -0.11684 0.85344) (xy -0.09144 0.87376) (xy -0.0635 0.889)
						(xy -0.03175 0.89916) (xy 0 0.9017) (xy 0.03175 0.89916) (xy 0.0635 0.889) (xy 0.09144 0.87376)
						(xy 0.11684 0.85344) (xy 0.13716 0.82804) (xy 0.1524 0.8001) (xy 0.16256 0.76835) (xy 0.1651 0.7366)
						(xy 0.1651 0.11938) (xy 0.17272 0.11176) (xy 0.19812 0.0762) (xy 0.2032 0.06604) (xy 0.20701 0.05715)
						(xy 0.21209 0.04699) (xy 0.2159 0.03683) (xy 0.21844 0.02667) (xy 0.22225 0.01524) (xy 0.22352 0.00508)
						(xy 0.22606 -0.00508) (xy 0.22733 -0.01651) (xy 0.22733 -0.02667) (xy 0.2286 -0.0381) (xy 0.22733 -0.04953)
						(xy 0.22733 -0.05969) (xy 0.22606 -0.07112) (xy 0.22352 -0.08128) (xy 0.22225 -0.09144) (xy 0.21844 -0.10287)
						(xy 0.2159 -0.11303) (xy 0.21209 -0.12319) (xy 0.20701 -0.13335) (xy 0.2032 -0.14224) (xy 0.19812 -0.1524)
						(xy 0.17272 -0.18796) (xy 0.1651 -0.19558) (xy 0.1651 -0.7366) (xy 0.16256 -0.76835) (xy 0.1524 -0.8001)
						(xy 0.13716 -0.82804) (xy 0.11684 -0.85344) (xy 0.09144 -0.87376) (xy 0.0635 -0.889) (xy 0.03175 -0.89916)
					)
					(width 0)
					(fill yes)
				)
			)
		)
		(pad "8" smd custom
			(at -29.550106 4.100068)
			(size 0.1143 0.1143)
			(layers "B.Cu" "B.Mask" "B.Paste")
			(net "GND")
			(options
				(clearance outline)
				(anchor circle)
			)
			(primitives
				(gr_poly
					(pts
						(xy 0 -0.9017) (xy -0.03175 -0.89916) (xy -0.0635 -0.889) (xy -0.09144 -0.87376) (xy -0.11684 -0.85344)
						(xy -0.13716 -0.82804) (xy -0.1524 -0.8001) (xy -0.16256 -0.76835) (xy -0.1651 -0.7366) (xy -0.1651 -0.11938)
						(xy -0.17272 -0.11176) (xy -0.19812 -0.0762) (xy -0.2032 -0.06604) (xy -0.20701 -0.05715) (xy -0.21209 -0.04699)
						(xy -0.2159 -0.03683) (xy -0.21844 -0.02667) (xy -0.22225 -0.01524) (xy -0.22352 -0.00508) (xy -0.22606 0.00508)
						(xy -0.22733 0.01651) (xy -0.22733 0.02667) (xy -0.2286 0.0381) (xy -0.22733 0.04953) (xy -0.22733 0.05969)
						(xy -0.22606 0.07112) (xy -0.22352 0.08128) (xy -0.22225 0.09144) (xy -0.21844 0.10287) (xy -0.2159 0.11303)
						(xy -0.21209 0.12319) (xy -0.20701 0.13335) (xy -0.2032 0.14224) (xy -0.19812 0.1524) (xy -0.17272 0.18796)
						(xy -0.1651 0.19558) (xy -0.1651 0.7366) (xy -0.16256 0.76835) (xy -0.1524 0.8001) (xy -0.13716 0.82804)
						(xy -0.11684 0.85344) (xy -0.09144 0.87376) (xy -0.0635 0.889) (xy -0.03175 0.89916) (xy 0 0.9017)
						(xy 0.03175 0.89916) (xy 0.0635 0.889) (xy 0.09144 0.87376) (xy 0.11684 0.85344) (xy 0.13716 0.82804)
						(xy 0.1524 0.8001) (xy 0.16256 0.76835) (xy 0.1651 0.7366) (xy 0.1651 0.19685) (xy 0.17272 0.18923)
						(xy 0.17907 0.18034) (xy 0.18669 0.17145) (xy 0.19177 0.16256) (xy 0.19812 0.15367) (xy 0.20828 0.13335)
						(xy 0.21971 0.10287) (xy 0.22225 0.09271) (xy 0.22479 0.08128) (xy 0.22606 0.07112) (xy 0.2286 0.05969)
						(xy 0.2286 0.01651) (xy 0.22606 0.00508) (xy 0.22479 -0.00508) (xy 0.22225 -0.01651) (xy 0.21971 -0.02667)
						(xy 0.20828 -0.05715) (xy 0.19812 -0.07747) (xy 0.19177 -0.08636) (xy 0.18669 -0.09525) (xy 0.17907 -0.10414)
						(xy 0.17272 -0.11303) (xy 0.1651 -0.12065) (xy 0.1651 -0.7366) (xy 0.16256 -0.76835) (xy 0.1524 -0.8001)
						(xy 0.13716 -0.82804) (xy 0.11684 -0.85344) (xy 0.09144 -0.87376) (xy 0.0635 -0.889) (xy 0.03175 -0.89916)
					)
					(width 0)
					(fill yes)
				)
			)
		)
		(pad "9" smd custom
			(at -29.249878 -4.100068)
			(size 0.1143 0.1143)
			(layers "B.Cu" "B.Mask" "B.Paste")
			(net "GND")
			(options
				(clearance outline)
				(anchor circle)
			)
			(primitives
				(gr_poly
					(pts
						(xy 0 -0.9017) (xy -0.03175 -0.89916) (xy -0.0635 -0.889) (xy -0.09144 -0.87376) (xy -0.11684 -0.85344)
						(xy -0.13716 -0.82804) (xy -0.1524 -0.8001) (xy -0.16256 -0.76835) (xy -0.1651 -0.7366) (xy -0.1651 -0.44958)
						(xy -0.17272 -0.44196) (xy -0.19812 -0.4064) (xy -0.2032 -0.39624) (xy -0.20701 -0.38735) (xy -0.21209 -0.37719)
						(xy -0.2159 -0.36703) (xy -0.21844 -0.35687) (xy -0.22225 -0.34544) (xy -0.22352 -0.33528) (xy -0.22606 -0.32512)
						(xy -0.22733 -0.31369) (xy -0.22733 -0.30353) (xy -0.2286 -0.2921) (xy -0.22733 -0.28067) (xy -0.22733 -0.27051)
						(xy -0.22606 -0.25908) (xy -0.22352 -0.24892) (xy -0.22225 -0.23876) (xy -0.21844 -0.22733) (xy -0.2159 -0.21717)
						(xy -0.21209 -0.20701) (xy -0.20701 -0.19685) (xy -0.2032 -0.18796) (xy -0.19812 -0.1778) (xy -0.17272 -0.14224)
						(xy -0.1651 -0.13462) (xy -0.1651 0.7366) (xy -0.16256 0.76835) (xy -0.1524 0.8001) (xy -0.13716 0.82804)
						(xy -0.11684 0.85344) (xy -0.09144 0.87376) (xy -0.0635 0.889) (xy -0.03175 0.89916) (xy 0 0.9017)
						(xy 0.03175 0.89916) (xy 0.0635 0.889) (xy 0.09144 0.87376) (xy 0.11684 0.85344) (xy 0.13716 0.82804)
						(xy 0.1524 0.8001) (xy 0.16256 0.76835) (xy 0.1651 0.7366) (xy 0.1651 -0.13462) (xy 0.17272 -0.14224)
						(xy 0.19812 -0.1778) (xy 0.2032 -0.18796) (xy 0.20701 -0.19685) (xy 0.21209 -0.20701) (xy 0.2159 -0.21717)
						(xy 0.21844 -0.22733) (xy 0.22225 -0.23876) (xy 0.22352 -0.24892) (xy 0.22606 -0.25908) (xy 0.22733 -0.27051)
						(xy 0.22733 -0.28067) (xy 0.2286 -0.2921) (xy 0.22733 -0.30353) (xy 0.22733 -0.31369) (xy 0.22606 -0.32512)
						(xy 0.22352 -0.33528) (xy 0.22225 -0.34544) (xy 0.21844 -0.35687) (xy 0.2159 -0.36703) (xy 0.21209 -0.37719)
						(xy 0.20701 -0.38735) (xy 0.2032 -0.39624) (xy 0.19812 -0.4064) (xy 0.17272 -0.44196) (xy 0.1651 -0.44958)
						(xy 0.1651 -0.7366) (xy 0.16256 -0.76835) (xy 0.1524 -0.8001) (xy 0.13716 -0.82804) (xy 0.11684 -0.85344)
						(xy 0.09144 -0.87376) (xy 0.0635 -0.889) (xy 0.03175 -0.89916)
					)
					(width 0)
					(fill yes)
				)
			)
		)
		(pad "10" smd custom
			(at -28.949904 4.100068)
			(size 0.1143 0.1143)
			(layers "B.Cu" "B.Mask" "B.Paste")
			(net "M_A_DQS_DN0")
			(options
				(clearance outline)
				(anchor circle)
			)
			(primitives
				(gr_poly
					(pts
						(xy 0 -0.9017) (xy -0.03175 -0.89916) (xy -0.0635 -0.889) (xy -0.09144 -0.87376) (xy -0.11684 -0.85344)
						(xy -0.13716 -0.82804) (xy -0.1524 -0.8001) (xy -0.16256 -0.76835) (xy -0.1651 -0.7366) (xy -0.1651 0.13462)
						(xy -0.17272 0.14224) (xy -0.19812 0.1778) (xy -0.2032 0.18796) (xy -0.20701 0.19685) (xy -0.21209 0.20701)
						(xy -0.2159 0.21717) (xy -0.21844 0.22733) (xy -0.22225 0.23876) (xy -0.22352 0.24892) (xy -0.22606 0.25908)
						(xy -0.22733 0.27051) (xy -0.22733 0.28067) (xy -0.2286 0.2921) (xy -0.22733 0.30353) (xy -0.22733 0.31369)
						(xy -0.22606 0.32512) (xy -0.22352 0.33528) (xy -0.22225 0.34544) (xy -0.21844 0.35687) (xy -0.2159 0.36703)
						(xy -0.21209 0.37719) (xy -0.20701 0.38735) (xy -0.2032 0.39624) (xy -0.19812 0.4064) (xy -0.17272 0.44196)
						(xy -0.1651 0.44958) (xy -0.1651 0.7366) (xy -0.16256 0.76835) (xy -0.1524 0.8001) (xy -0.13716 0.82804)
						(xy -0.11684 0.85344) (xy -0.09144 0.87376) (xy -0.0635 0.889) (xy -0.03175 0.89916) (xy 0 0.9017)
						(xy 0.03175 0.89916) (xy 0.0635 0.889) (xy 0.09144 0.87376) (xy 0.11684 0.85344) (xy 0.13716 0.82804)
						(xy 0.1524 0.8001) (xy 0.16256 0.76835) (xy 0.1651 0.7366) (xy 0.1651 0.44958) (xy 0.17272 0.44196)
						(xy 0.19812 0.4064) (xy 0.2032 0.39624) (xy 0.20701 0.38735) (xy 0.21209 0.37719) (xy 0.2159 0.36703)
						(xy 0.21844 0.35687) (xy 0.22225 0.34544) (xy 0.22352 0.33528) (xy 0.22606 0.32512) (xy 0.22733 0.31369)
						(xy 0.22733 0.30353) (xy 0.2286 0.2921) (xy 0.22733 0.28067) (xy 0.22733 0.27051) (xy 0.22606 0.25908)
						(xy 0.22352 0.24892) (xy 0.22225 0.23876) (xy 0.21844 0.22733) (xy 0.2159 0.21717) (xy 0.21209 0.20701)
						(xy 0.20701 0.19685) (xy 0.2032 0.18796) (xy 0.19812 0.1778) (xy 0.17272 0.14224) (xy 0.1651 0.13462)
						(xy 0.1651 -0.7366) (xy 0.16256 -0.76835) (xy 0.1524 -0.8001) (xy 0.13716 -0.82804) (xy 0.11684 -0.85344)
						(xy 0.09144 -0.87376) (xy 0.0635 -0.889) (xy 0.03175 -0.89916)
					)
					(width 0)
					(fill yes)
				)
			)
		)
		(pad "11" smd custom
			(at -28.64993 -4.100068)
			(size 0.1143 0.1143)
			(layers "B.Cu" "B.Mask" "B.Paste")
			(net "GND")
			(options
				(clearance outline)
				(anchor circle)
			)
			(primitives
				(gr_poly
					(pts
						(xy 0 -0.9017) (xy -0.03175 -0.89916) (xy -0.0635 -0.889) (xy -0.09144 -0.87376) (xy -0.11684 -0.85344)
						(xy -0.13716 -0.82804) (xy -0.1524 -0.8001) (xy -0.16256 -0.76835) (xy -0.1651 -0.7366) (xy -0.1651 -0.19685)
						(xy -0.17272 -0.18923) (xy -0.17907 -0.18034) (xy -0.18669 -0.17145) (xy -0.19177 -0.16256) (xy -0.19812 -0.15367)
						(xy -0.20828 -0.13335) (xy -0.21971 -0.10287) (xy -0.22225 -0.09271) (xy -0.22479 -0.08128) (xy -0.22606 -0.07112)
						(xy -0.2286 -0.05969) (xy -0.2286 -0.01651) (xy -0.22606 -0.00508) (xy -0.22479 0.00508) (xy -0.22225 0.01651)
						(xy -0.21971 0.02667) (xy -0.20828 0.05715) (xy -0.19812 0.07747) (xy -0.19177 0.08636) (xy -0.18669 0.09525)
						(xy -0.17907 0.10414) (xy -0.17272 0.11303) (xy -0.1651 0.12065) (xy -0.1651 0.7366) (xy -0.16256 0.76835)
						(xy -0.1524 0.8001) (xy -0.13716 0.82804) (xy -0.11684 0.85344) (xy -0.09144 0.87376) (xy -0.0635 0.889)
						(xy -0.03175 0.89916) (xy 0 0.9017) (xy 0.03175 0.89916) (xy 0.0635 0.889) (xy 0.09144 0.87376)
						(xy 0.11684 0.85344) (xy 0.13716 0.82804) (xy 0.1524 0.8001) (xy 0.16256 0.76835) (xy 0.1651 0.7366)
						(xy 0.1651 0.11938) (xy 0.17272 0.11176) (xy 0.19812 0.0762) (xy 0.2032 0.06604) (xy 0.20701 0.05715)
						(xy 0.21209 0.04699) (xy 0.2159 0.03683) (xy 0.21844 0.02667) (xy 0.22225 0.01524) (xy 0.22352 0.00508)
						(xy 0.22606 -0.00508) (xy 0.22733 -0.01651) (xy 0.22733 -0.02667) (xy 0.2286 -0.0381) (xy 0.22733 -0.04953)
						(xy 0.22733 -0.05969) (xy 0.22606 -0.07112) (xy 0.22352 -0.08128) (xy 0.22225 -0.09144) (xy 0.21844 -0.10287)
						(xy 0.2159 -0.11303) (xy 0.21209 -0.12319) (xy 0.20701 -0.13335) (xy 0.2032 -0.14224) (xy 0.19812 -0.1524)
						(xy 0.17272 -0.18796) (xy 0.1651 -0.19558) (xy 0.1651 -0.7366) (xy 0.16256 -0.76835) (xy 0.1524 -0.8001)
						(xy 0.13716 -0.82804) (xy 0.11684 -0.85344) (xy 0.09144 -0.87376) (xy 0.0635 -0.889) (xy 0.03175 -0.89916)
					)
					(width 0)
					(fill yes)
				)
			)
		)
		(pad "12" smd custom
			(at -28.349956 4.100068)
			(size 0.1143 0.1143)
			(layers "B.Cu" "B.Mask" "B.Paste")
			(net "M_A_DQS_DP0")
			(options
				(clearance outline)
				(anchor circle)
			)
			(primitives
				(gr_poly
					(pts
						(xy 0 -0.9017) (xy -0.03175 -0.89916) (xy -0.0635 -0.889) (xy -0.09144 -0.87376) (xy -0.11684 -0.85344)
						(xy -0.13716 -0.82804) (xy -0.1524 -0.8001) (xy -0.16256 -0.76835) (xy -0.1651 -0.7366) (xy -0.1651 -0.11938)
						(xy -0.17272 -0.11176) (xy -0.19812 -0.0762) (xy -0.2032 -0.06604) (xy -0.20701 -0.05715) (xy -0.21209 -0.04699)
						(xy -0.2159 -0.03683) (xy -0.21844 -0.02667) (xy -0.22225 -0.01524) (xy -0.22352 -0.00508) (xy -0.22606 0.00508)
						(xy -0.22733 0.01651) (xy -0.22733 0.02667) (xy -0.2286 0.0381) (xy -0.22733 0.04953) (xy -0.22733 0.05969)
						(xy -0.22606 0.07112) (xy -0.22352 0.08128) (xy -0.22225 0.09144) (xy -0.21844 0.10287) (xy -0.2159 0.11303)
						(xy -0.21209 0.12319) (xy -0.20701 0.13335) (xy -0.2032 0.14224) (xy -0.19812 0.1524) (xy -0.17272 0.18796)
						(xy -0.1651 0.19558) (xy -0.1651 0.7366) (xy -0.16256 0.76835) (xy -0.1524 0.8001) (xy -0.13716 0.82804)
						(xy -0.11684 0.85344) (xy -0.09144 0.87376) (xy -0.0635 0.889) (xy -0.03175 0.89916) (xy 0 0.9017)
						(xy 0.03175 0.89916) (xy 0.0635 0.889) (xy 0.09144 0.87376) (xy 0.11684 0.85344) (xy 0.13716 0.82804)
						(xy 0.1524 0.8001) (xy 0.16256 0.76835) (xy 0.1651 0.7366) (xy 0.1651 0.19685) (xy 0.17272 0.18923)
						(xy 0.17907 0.18034) (xy 0.18669 0.17145) (xy 0.19177 0.16256) (xy 0.19812 0.15367) (xy 0.20828 0.13335)
						(xy 0.21971 0.10287) (xy 0.22225 0.09271) (xy 0.22479 0.08128) (xy 0.22606 0.07112) (xy 0.2286 0.05969)
						(xy 0.2286 0.01651) (xy 0.22606 0.00508) (xy 0.22479 -0.00508) (xy 0.22225 -0.01651) (xy 0.21971 -0.02667)
						(xy 0.20828 -0.05715) (xy 0.19812 -0.07747) (xy 0.19177 -0.08636) (xy 0.18669 -0.09525) (xy 0.17907 -0.10414)
						(xy 0.17272 -0.11303) (xy 0.1651 -0.12065) (xy 0.1651 -0.7366) (xy 0.16256 -0.76835) (xy 0.1524 -0.8001)
						(xy 0.13716 -0.82804) (xy 0.11684 -0.85344) (xy 0.09144 -0.87376) (xy 0.0635 -0.889) (xy 0.03175 -0.89916)
					)
					(width 0)
					(fill yes)
				)
			)
		)
		(pad "13" smd custom
			(at -28.049982 -4.100068)
			(size 0.1143 0.1143)
			(layers "B.Cu" "B.Mask" "B.Paste")
			(net "M_A_DQ2")
			(options
				(clearance outline)
				(anchor circle)
			)
			(primitives
				(gr_poly
					(pts
						(xy 0 -0.9017) (xy -0.03175 -0.89916) (xy -0.0635 -0.889) (xy -0.09144 -0.87376) (xy -0.11684 -0.85344)
						(xy -0.13716 -0.82804) (xy -0.1524 -0.8001) (xy -0.16256 -0.76835) (xy -0.1651 -0.7366) (xy -0.1651 -0.44958)
						(xy -0.17272 -0.44196) (xy -0.19812 -0.4064) (xy -0.2032 -0.39624) (xy -0.20701 -0.38735) (xy -0.21209 -0.37719)
						(xy -0.2159 -0.36703) (xy -0.21844 -0.35687) (xy -0.22225 -0.34544) (xy -0.22352 -0.33528) (xy -0.22606 -0.32512)
						(xy -0.22733 -0.31369) (xy -0.22733 -0.30353) (xy -0.2286 -0.2921) (xy -0.22733 -0.28067) (xy -0.22733 -0.27051)
						(xy -0.22606 -0.25908) (xy -0.22352 -0.24892) (xy -0.22225 -0.23876) (xy -0.21844 -0.22733) (xy -0.2159 -0.21717)
						(xy -0.21209 -0.20701) (xy -0.20701 -0.19685) (xy -0.2032 -0.18796) (xy -0.19812 -0.1778) (xy -0.17272 -0.14224)
						(xy -0.1651 -0.13462) (xy -0.1651 0.7366) (xy -0.16256 0.76835) (xy -0.1524 0.8001) (xy -0.13716 0.82804)
						(xy -0.11684 0.85344) (xy -0.09144 0.87376) (xy -0.0635 0.889) (xy -0.03175 0.89916) (xy 0 0.9017)
						(xy 0.03175 0.89916) (xy 0.0635 0.889) (xy 0.09144 0.87376) (xy 0.11684 0.85344) (xy 0.13716 0.82804)
						(xy 0.1524 0.8001) (xy 0.16256 0.76835) (xy 0.1651 0.7366) (xy 0.1651 -0.13462) (xy 0.17272 -0.14224)
						(xy 0.19812 -0.1778) (xy 0.2032 -0.18796) (xy 0.20701 -0.19685) (xy 0.21209 -0.20701) (xy 0.2159 -0.21717)
						(xy 0.21844 -0.22733) (xy 0.22225 -0.23876) (xy 0.22352 -0.24892) (xy 0.22606 -0.25908) (xy 0.22733 -0.27051)
						(xy 0.22733 -0.28067) (xy 0.2286 -0.2921) (xy 0.22733 -0.30353) (xy 0.22733 -0.31369) (xy 0.22606 -0.32512)
						(xy 0.22352 -0.33528) (xy 0.22225 -0.34544) (xy 0.21844 -0.35687) (xy 0.2159 -0.36703) (xy 0.21209 -0.37719)
						(xy 0.20701 -0.38735) (xy 0.2032 -0.39624) (xy 0.19812 -0.4064) (xy 0.17272 -0.44196) (xy 0.1651 -0.44958)
						(xy 0.1651 -0.7366) (xy 0.16256 -0.76835) (xy 0.1524 -0.8001) (xy 0.13716 -0.82804) (xy 0.11684 -0.85344)
						(xy 0.09144 -0.87376) (xy 0.0635 -0.889) (xy 0.03175 -0.89916)
					)
					(width 0)
					(fill yes)
				)
			)
		)
	)
)
